(kicad_pcb
	(version 20260206)
	(generator "pcbnew")
	(generator_version "10.0")
	(general
		(thickness 1.6)
		(legacy_teardrops no)
	)
	(paper "A4")
	(title_block
		(title "04192023_DAF0TMB3IC0_F0TG_MB_C_brd_V02_OCP.brd")
		(comment 1 "Grand Teton / footprints 2989-2993 of 8354")
	)
	(layers
		(0 "F.Cu" signal "TOP")
		(4 "In1.Cu" signal "GND")
		(6 "In2.Cu" signal "IN1")
		(8 "In3.Cu" signal "GND1")
		(10 "In4.Cu" signal "IN2")
		(12 "In5.Cu" signal "GND2")
		(14 "In6.Cu" signal "IN3")
		(16 "In7.Cu" signal "GND3")
		(18 "In8.Cu" signal "VCC")
		(20 "In9.Cu" signal "VCC1")
		(22 "In10.Cu" signal "GND4")
		(24 "In11.Cu" signal "IN4")
		(26 "In12.Cu" signal "GND5")
		(28 "In13.Cu" signal "IN5")
		(30 "In14.Cu" signal "GND6")
		(32 "In15.Cu" signal "IN6")
		(34 "In16.Cu" signal "GND7")
		(2 "B.Cu" signal "BOTTOM")
		(9 "F.Adhes" user "F.Adhesive")
		(11 "B.Adhes" user "B.Adhesive")
		(13 "F.Paste" user "Package Geometry/Pastemask Top")
		(15 "B.Paste" user "Package Geometry/Pastemask Bottom")
		(5 "F.SilkS" user "Ref Des/Silkscreen Top")
		(7 "B.SilkS" user "Ref Des/Silkscreen Bottom")
		(1 "F.Mask" user "Board Geometry/Soldermask Top")
		(3 "B.Mask" user "Board Geometry/Soldermask Bottom")
		(17 "Dwgs.User" user "User.Drawings")
		(19 "Cmts.User" user "User.Comments")
		(21 "Eco1.User" user "User.Eco1")
		(23 "Eco2.User" user "User.Eco2")
		(25 "Edge.Cuts" user "Board Geometry/Outline")
		(27 "Margin" user)
		(31 "F.CrtYd" user "Package Geometry/Place Bound Top")
		(29 "B.CrtYd" user "Package Geometry/Place Bound Bottom")
		(35 "F.Fab" user "Ref Des/Assembly Top")
		(33 "B.Fab" user "Ref Des/Assembly Bottom")
	)
	(footprint ""
		(layer "F.Cu")
		(at 66.731896 -333.26578 90)
		(property "Reference" "PR516"
			(at 0 0 90)
			(layer "F.SilkS")
			(hide yes)
			(effects
				(font
					(size 1.27 1.27)
				)
			)
		)
		(property "Value" ""
			(at 0 0 90)
			(layer "F.Fab")
			(effects
				(font
					(size 1.27 1.27)
				)
			)
		)
		(duplicate_pad_numbers_are_jumpers no)
		(fp_line
			(start 0.7874 -0.4064)
			(end 0.7874 0.4064)
			(stroke
				(width 0.1524)
				(type default)
			)
			(layer "F.SilkS")
		)
		(fp_line
			(start -0.7874 -0.4064)
			(end 0.7874 -0.4064)
			(stroke
				(width 0.1524)
				(type default)
			)
			(layer "F.SilkS")
		)
		(fp_line
			(start 0.7874 0.4064)
			(end -0.7874 0.4064)
			(stroke
				(width 0.1524)
				(type default)
			)
			(layer "F.SilkS")
		)
		(fp_line
			(start -0.7874 0.4064)
			(end -0.7874 -0.4064)
			(stroke
				(width 0.1524)
				(type default)
			)
			(layer "F.SilkS")
		)
		(fp_line
			(start -0.12065 -0.305054)
			(end -0.12065 -0.2794)
			(stroke
				(width 0.1)
				(type default)
			)
			(layer "F.Fab")
		)
		(fp_line
			(start -0.67945 -0.305054)
			(end -0.12065 -0.305054)
			(stroke
				(width 0.1)
				(type default)
			)
			(layer "F.Fab")
		)
		(fp_line
			(start 0.67945 -0.3048)
			(end 0.67945 0.3048)
			(stroke
				(width 0.1)
				(type default)
			)
			(layer "F.Fab")
		)
		(fp_line
			(start 0.12065 -0.3048)
			(end 0.67945 -0.3048)
			(stroke
				(width 0.1)
				(type default)
			)
			(layer "F.Fab")
		)
		(fp_line
			(start 0.12065 -0.2794)
			(end 0.12065 -0.3048)
			(stroke
				(width 0.1)
				(type default)
			)
			(layer "F.Fab")
		)
		(fp_line
			(start -0.12065 -0.2794)
			(end 0.12065 -0.2794)
			(stroke
				(width 0.1)
				(type default)
			)
			(layer "F.Fab")
		)
		(fp_line
			(start 0.120396 0.2794)
			(end -0.12065 0.2794)
			(stroke
				(width 0.1)
				(type default)
			)
			(layer "F.Fab")
		)
		(fp_line
			(start -0.12065 0.2794)
			(end -0.12065 0.3048)
			(stroke
				(width 0.1)
				(type default)
			)
			(layer "F.Fab")
		)
		(fp_line
			(start 0.67945 0.3048)
			(end 0.120396 0.3048)
			(stroke
				(width 0.1)
				(type default)
			)
			(layer "F.Fab")
		)
		(fp_line
			(start 0.120396 0.3048)
			(end 0.120396 0.2794)
			(stroke
				(width 0.1)
				(type default)
			)
			(layer "F.Fab")
		)
		(fp_line
			(start -0.12065 0.3048)
			(end -0.67945 0.3048)
			(stroke
				(width 0.1)
				(type default)
			)
			(layer "F.Fab")
		)
		(fp_line
			(start -0.67945 0.3048)
			(end -0.67945 -0.305054)
			(stroke
				(width 0.1)
				(type default)
			)
			(layer "F.Fab")
		)
		(pad "1" smd circle
			(at -0.40005 0 90)
			(size 0 0)
			(layers "F.Cu" "F.Mask" "F.Paste")
			(net "SW_PVDDCR_CPU1_P1_SW3_RC")
		)
		(pad "2" smd circle
			(at 0.40005 0 90)
			(size 0 0)
			(layers "F.Cu" "F.Mask" "F.Paste")
			(net "GND")
		)
	)
	(footprint ""
		(layer "F.Cu")
		(at 120.396 -425.704 180)
		(property "Reference" "R3454"
			(at 0 0 180)
			(layer "F.SilkS")
			(hide yes)
			(effects
				(font
					(size 1.27 1.27)
				)
			)
		)
		(property "Value" ""
			(at 0 0 180)
			(layer "F.Fab")
			(effects
				(font
					(size 1.27 1.27)
				)
			)
		)
		(duplicate_pad_numbers_are_jumpers no)
		(fp_line
			(start 0.7874 0.4064)
			(end -0.7874 0.4064)
			(stroke
				(width 0.1524)
				(type default)
			)
			(layer "F.SilkS")
		)
		(fp_line
			(start 0.7874 -0.4064)
			(end 0.7874 0.4064)
			(stroke
				(width 0.1524)
				(type default)
			)
			(layer "F.SilkS")
		)
		(fp_line
			(start -0.7874 0.4064)
			(end -0.7874 -0.4064)
			(stroke
				(width 0.1524)
				(type default)
			)
			(layer "F.SilkS")
		)
		(fp_line
			(start -0.7874 -0.4064)
			(end 0.7874 -0.4064)
			(stroke
				(width 0.1524)
				(type default)
			)
			(layer "F.SilkS")
		)
		(fp_line
			(start 0.67945 0.3048)
			(end 0.120396 0.3048)
			(stroke
				(width 0.1)
				(type default)
			)
			(layer "F.Fab")
		)
		(fp_line
			(start 0.67945 -0.3048)
			(end 0.67945 0.3048)
			(stroke
				(width 0.1)
				(type default)
			)
			(layer "F.Fab")
		)
		(fp_line
			(start 0.12065 -0.2794)
			(end 0.12065 -0.3048)
			(stroke
				(width 0.1)
				(type default)
			)
			(layer "F.Fab")
		)
		(fp_line
			(start 0.12065 -0.3048)
			(end 0.67945 -0.3048)
			(stroke
				(width 0.1)
				(type default)
			)
			(layer "F.Fab")
		)
		(fp_line
			(start 0.120396 0.3048)
			(end 0.120396 0.2794)
			(stroke
				(width 0.1)
				(type default)
			)
			(layer "F.Fab")
		)
		(fp_line
			(start 0.120396 0.2794)
			(end -0.12065 0.2794)
			(stroke
				(width 0.1)
				(type default)
			)
			(layer "F.Fab")
		)
		(fp_line
			(start -0.12065 0.3048)
			(end -0.67945 0.3048)
			(stroke
				(width 0.1)
				(type default)
			)
			(layer "F.Fab")
		)
		(fp_line
			(start -0.12065 0.2794)
			(end -0.12065 0.3048)
			(stroke
				(width 0.1)
				(type default)
			)
			(layer "F.Fab")
		)
		(fp_line
			(start -0.12065 -0.2794)
			(end 0.12065 -0.2794)
			(stroke
				(width 0.1)
				(type default)
			)
			(layer "F.Fab")
		)
		(fp_line
			(start -0.12065 -0.305054)
			(end -0.12065 -0.2794)
			(stroke
				(width 0.1)
				(type default)
			)
			(layer "F.Fab")
		)
		(fp_line
			(start -0.67945 0.3048)
			(end -0.67945 -0.305054)
			(stroke
				(width 0.1)
				(type default)
			)
			(layer "F.Fab")
		)
		(fp_line
			(start -0.67945 -0.305054)
			(end -0.12065 -0.305054)
			(stroke
				(width 0.1)
				(type default)
			)
			(layer "F.Fab")
		)
		(pad "1" smd circle
			(at -0.40005 0 180)
			(size 0 0)
			(layers "F.Cu" "F.Mask" "F.Paste")
			(net "GPU_FPGA_BOOT_EN_BUF_R")
		)
		(pad "2" smd circle
			(at 0.40005 0 180)
			(size 0 0)
			(layers "F.Cu" "F.Mask" "F.Paste")
			(net "GND")
		)
	)
	(footprint ""
		(layer "F.Cu")
		(at 410.796486 -134.807706)
		(property "Reference" "PC1648"
			(at 0 0 0)
			(layer "F.SilkS")
			(hide yes)
			(effects
				(font
					(size 1.27 1.27)
				)
			)
		)
		(property "Value" ""
			(at 0 0 0)
			(layer "F.Fab")
			(effects
				(font
					(size 1.27 1.27)
				)
			)
		)
		(duplicate_pad_numbers_are_jumpers no)
		(fp_line
			(start -0.7874 -0.4064)
			(end 0.7874 -0.4064)
			(stroke
				(width 0.1524)
				(type default)
			)
			(layer "F.SilkS")
		)
		(fp_line
			(start -0.7874 0.4064)
			(end -0.7874 -0.4064)
			(stroke
				(width 0.1524)
				(type default)
			)
			(layer "F.SilkS")
		)
		(fp_line
			(start 0.7874 -0.4064)
			(end 0.7874 0.4064)
			(stroke
				(width 0.1524)
				(type default)
			)
			(layer "F.SilkS")
		)
		(fp_line
			(start 0.7874 0.4064)
			(end -0.7874 0.4064)
			(stroke
				(width 0.1524)
				(type default)
			)
			(layer "F.SilkS")
		)
		(fp_line
			(start -0.67945 -0.305054)
			(end -0.12065 -0.305054)
			(stroke
				(width 0.1)
				(type default)
			)
			(layer "F.Fab")
		)
		(fp_line
			(start -0.67945 0.3048)
			(end -0.67945 -0.305054)
			(stroke
				(width 0.1)
				(type default)
			)
			(layer "F.Fab")
		)
		(fp_line
			(start -0.12065 -0.305054)
			(end -0.12065 -0.2794)
			(stroke
				(width 0.1)
				(type default)
			)
			(layer "F.Fab")
		)
		(fp_line
			(start -0.12065 -0.2794)
			(end 0.12065 -0.2794)
			(stroke
				(width 0.1)
				(type default)
			)
			(layer "F.Fab")
		)
		(fp_line
			(start -0.12065 0.2794)
			(end -0.12065 0.3048)
			(stroke
				(width 0.1)
				(type default)
			)
			(layer "F.Fab")
		)
		(fp_line
			(start -0.12065 0.3048)
			(end -0.67945 0.3048)
			(stroke
				(width 0.1)
				(type default)
			)
			(layer "F.Fab")
		)
		(fp_line
			(start 0.120396 0.2794)
			(end -0.12065 0.2794)
			(stroke
				(width 0.1)
				(type default)
			)
			(layer "F.Fab")
		)
		(fp_line
			(start 0.120396 0.3048)
			(end 0.120396 0.2794)
			(stroke
				(width 0.1)
				(type default)
			)
			(layer "F.Fab")
		)
		(fp_line
			(start 0.12065 -0.3048)
			(end 0.67945 -0.3048)
			(stroke
				(width 0.1)
				(type default)
			)
			(layer "F.Fab")
		)
		(fp_line
			(start 0.12065 -0.2794)
			(end 0.12065 -0.3048)
			(stroke
				(width 0.1)
				(type default)
			)
			(layer "F.Fab")
		)
		(fp_line
			(start 0.67945 -0.3048)
			(end 0.67945 0.3048)
			(stroke
				(width 0.1)
				(type default)
			)
			(layer "F.Fab")
		)
		(fp_line
			(start 0.67945 0.3048)
			(end 0.120396 0.3048)
			(stroke
				(width 0.1)
				(type default)
			)
			(layer "F.Fab")
		)
		(pad "1" smd circle
			(at -0.40005 0)
			(size 0 0)
			(layers "F.Cu" "F.Mask" "F.Paste")
			(net "P12V_AUX")
		)
		(pad "2" smd circle
			(at 0.40005 0)
			(size 0 0)
			(layers "F.Cu" "F.Mask" "F.Paste")
			(net "GND")
		)
	)
	(footprint ""
		(layer "F.Cu")
		(at 395.279118 -76.305664)
		(property "Reference" "U55"
			(at -0.526288 -4.18084 0)
			(unlocked yes)
			(layer "F.SilkS")
			(effects
				(font
					(size 0.7874 0.5842)
					(thickness 0.1524)
				)
			)
		)
		(property "Value" ""
			(at 0 0 0)
			(layer "F.Fab")
			(effects
				(font
					(size 1.27 1.27)
				)
			)
		)
		(duplicate_pad_numbers_are_jumpers no)
		(fp_line
			(start -1.500124 -1.500124)
			(end -1.004062 -1.500124)
			(stroke
				(width 0.1524)
				(type default)
			)
			(layer "F.SilkS")
		)
		(fp_line
			(start -1.500124 -1.004062)
			(end -1.500124 -1.500124)
			(stroke
				(width 0.1524)
				(type default)
			)
			(layer "F.SilkS")
		)
		(fp_line
			(start -1.500124 1.500124)
			(end -1.500124 1.004062)
			(stroke
				(width 0.1524)
				(type default)
			)
			(layer "F.SilkS")
		)
		(fp_line
			(start -1.004062 1.500124)
			(end -1.500124 1.500124)
			(stroke
				(width 0.1524)
				(type default)
			)
			(layer "F.SilkS")
		)
		(fp_line
			(start 1.004062 -1.500124)
			(end 1.500124 -1.500124)
			(stroke
				(width 0.1524)
				(type default)
			)
			(layer "F.SilkS")
		)
		(fp_line
			(start 1.500124 -1.500124)
			(end 1.500124 -1.004062)
			(stroke
				(width 0.1524)
				(type default)
			)
			(layer "F.SilkS")
		)
		(fp_line
			(start 1.500124 1.004062)
			(end 1.500124 1.500124)
			(stroke
				(width 0.1524)
				(type default)
			)
			(layer "F.SilkS")
		)
		(fp_line
			(start 1.500124 1.500124)
			(end 1.004062 1.500124)
			(stroke
				(width 0.1524)
				(type default)
			)
			(layer "F.SilkS")
		)
		(fp_poly
			(pts
				(xy -1.271016 -2.21869) (xy -2.285238 -2.159254) (xy -1.718564 -1.17475)
			)
			(stroke
				(width 0)
				(type default)
			)
			(fill yes)
			(layer "F.SilkS")
		)
		(fp_line
			(start -1.500124 -1.500124)
			(end 1.500124 -1.500124)
			(stroke
				(width 0.1)
				(type default)
			)
			(layer "F.Fab")
		)
		(fp_line
			(start -1.500124 1.500124)
			(end -1.500124 -1.500124)
			(stroke
				(width 0.1)
				(type default)
			)
			(layer "F.Fab")
		)
		(fp_line
			(start 1.500124 -1.500124)
			(end 1.500124 1.500124)
			(stroke
				(width 0.1)
				(type default)
			)
			(layer "F.Fab")
		)
		(fp_line
			(start 1.500124 1.500124)
			(end -1.500124 1.500124)
			(stroke
				(width 0.1)
				(type default)
			)
			(layer "F.Fab")
		)
		(fp_poly
			(pts
				(xy -2.847848 -1.258062) (xy -2.847848 -0.242062) (xy -1.831848 -0.750062)
			)
			(stroke
				(width 0)
				(type default)
			)
			(fill yes)
			(layer "F.Fab")
		)
		(pad "1" smd rect
			(at -1.400048 -0.750062 270)
			(size 0.2286 0.6096)
			(layers "F.Cu" "F.Mask" "F.Paste")
			(net "INA230_6_A1")
		)
		(pad "2" smd rect
			(at -1.400048 -0.249936 270)
			(size 0.2286 0.6096)
			(layers "F.Cu" "F.Mask" "F.Paste")
			(net "INA230_6_A0")
		)
		(pad "3" smd rect
			(at -1.400048 0.249936 270)
			(size 0.2286 0.6096)
			(layers "F.Cu" "F.Mask" "F.Paste")
			(net "P12V_OCP_SFF_ADC_ALERT_R")
		)
		(pad "4" smd rect
			(at -1.400048 0.750062 270)
			(size 0.2286 0.6096)
			(layers "F.Cu" "F.Mask" "F.Paste")
			(net "SMB_INA230_6_3V3AUX_SDA_R1")
		)
		(pad "5" smd rect
			(at -0.750062 1.400048)
			(size 0.2286 0.6096)
			(layers "F.Cu" "F.Mask" "F.Paste")
			(net "SMB_INA230_6_3V3AUX_SCL_R1")
		)
		(pad "6" smd rect
			(at -0.249936 1.400048)
			(size 0.2286 0.6096)
			(layers "F.Cu" "F.Mask" "F.Paste")
			(net "NC_INA230_6_NC0")
		)
		(pad "7" smd rect
			(at 0.249936 1.400048)
			(size 0.2286 0.6096)
			(layers "F.Cu" "F.Mask" "F.Paste")
			(net "NC_INA230_6_NC1")
		)
		(pad "8" smd rect
			(at 0.750062 1.400048)
			(size 0.2286 0.6096)
			(layers "F.Cu" "F.Mask" "F.Paste")
			(net "NC_INA230_6_NC2")
		)
		(pad "9" smd rect
			(at 1.400048 0.750062 270)
			(size 0.2286 0.6096)
			(layers "F.Cu" "F.Mask" "F.Paste")
			(net "P3V3_AUX")
		)
		(pad "10" smd rect
			(at 1.400048 0.249936 270)
			(size 0.2286 0.6096)
			(layers "F.Cu" "F.Mask" "F.Paste")
			(net "GND")
		)
		(pad "11" smd rect
			(at 1.400048 -0.249936 270)
			(size 0.2286 0.6096)
			(layers "F.Cu" "F.Mask" "F.Paste")
			(net "P12V_OCP_SFF")
		)
		(pad "12" smd rect
			(at 1.400048 -0.750062 270)
			(size 0.2286 0.6096)
			(layers "F.Cu" "F.Mask" "F.Paste")
			(net "VSENSE_P12V_INA230_6_INN")
		)
		(pad "13" smd rect
			(at 0.750062 -1.400048)
			(size 0.2286 0.6096)
			(layers "F.Cu" "F.Mask" "F.Paste")
			(net "VSENSE_P12V_INA230_6_INP")
		)
		(pad "14" smd rect
			(at 0.249936 -1.400048)
			(size 0.2286 0.6096)
			(layers "F.Cu" "F.Mask" "F.Paste")
			(net "NC_INA230_6_NC3")
		)
		(pad "15" smd rect
			(at -0.249936 -1.400048)
			(size 0.2286 0.6096)
			(layers "F.Cu" "F.Mask" "F.Paste")
			(net "NC_INA230_6_NC4")
		)
		(pad "16" smd rect
			(at -0.750062 -1.400048)
			(size 0.2286 0.6096)
			(layers "F.Cu" "F.Mask" "F.Paste")
			(net "NC_INA230_6_NC5")
		)
		(pad "TH" smd rect
			(at 0 0)
			(size 1.7018 1.7018)
			(layers "F.Cu" "F.Mask" "F.Paste")
			(net "GND")
		)
		(zone
			(layer "F.Cu")
			(hatch none 0.5)
			(connect_pads
				(clearance 0)
			)
			(min_thickness 0.25)
			(keepout
				(tracks not_allowed)
				(vias allowed)
				(pads allowed)
				(copperpour not_allowed)
				(footprints allowed)
			)
			(placement
				(enabled no)
				(sheetname "")
			)
			(fill
				(thermal_gap 0.5)
				(thermal_bridge_width 0.5)
				(island_removal_mode 0)
			)
			(polygon
				(pts
					(xy 394.23467 -76.331064) (xy 394.23467 -77.350112) (xy 396.323566 -77.350112) (xy 396.323566 -75.261216)
					(xy 394.23467 -75.261216) (xy 394.23467 -76.305664) (xy 394.377418 -76.305664) (xy 394.377418 -75.403964)
					(xy 396.180818 -75.403964) (xy 396.180818 -77.207364) (xy 394.377418 -77.207364) (xy 394.377418 -76.331064)
				)
			)
		)
	)
	(footprint ""
		(layer "F.Cu")
		(at 213.19744 -30.246828 90)
		(property "Reference" "R4091"
			(at 0 0 90)
			(layer "F.SilkS")
			(hide yes)
			(effects
				(font
					(size 1.27 1.27)
				)
			)
		)
		(property "Value" ""
			(at 0 0 90)
			(layer "F.Fab")
			(effects
				(font
					(size 1.27 1.27)
				)
			)
		)
		(duplicate_pad_numbers_are_jumpers no)
		(fp_line
			(start 0.7874 -0.4064)
			(end 0.7874 0.4064)
			(stroke
				(width 0.1524)
				(type default)
			)
			(layer "F.SilkS")
		)
		(fp_line
			(start -0.7874 -0.4064)
			(end 0.7874 -0.4064)
			(stroke
				(width 0.1524)
				(type default)
			)
			(layer "F.SilkS")
		)
		(fp_line
			(start 0.7874 0.4064)
			(end -0.7874 0.4064)
			(stroke
				(width 0.1524)
				(type default)
			)
			(layer "F.SilkS")
		)
		(fp_line
			(start -0.7874 0.4064)
			(end -0.7874 -0.4064)
			(stroke
				(width 0.1524)
				(type default)
			)
			(layer "F.SilkS")
		)
		(fp_line
			(start -0.12065 -0.305054)
			(end -0.12065 -0.2794)
			(stroke
				(width 0.1)
				(type default)
			)
			(layer "F.Fab")
		)
		(fp_line
			(start -0.67945 -0.305054)
			(end -0.12065 -0.305054)
			(stroke
				(width 0.1)
				(type default)
			)
			(layer "F.Fab")
		)
		(fp_line
			(start 0.67945 -0.3048)
			(end 0.67945 0.3048)
			(stroke
				(width 0.1)
				(type default)
			)
			(layer "F.Fab")
		)
		(fp_line
			(start 0.12065 -0.3048)
			(end 0.67945 -0.3048)
			(stroke
				(width 0.1)
				(type default)
			)
			(layer "F.Fab")
		)
		(fp_line
			(start 0.12065 -0.2794)
			(end 0.12065 -0.3048)
			(stroke
				(width 0.1)
				(type default)
			)
			(layer "F.Fab")
		)
		(fp_line
			(start -0.12065 -0.2794)
			(end 0.12065 -0.2794)
			(stroke
				(width 0.1)
				(type default)
			)
			(layer "F.Fab")
		)
		(fp_line
			(start 0.120396 0.2794)
			(end -0.12065 0.2794)
			(stroke
				(width 0.1)
				(type default)
			)
			(layer "F.Fab")
		)
		(fp_line
			(start -0.12065 0.2794)
			(end -0.12065 0.3048)
			(stroke
				(width 0.1)
				(type default)
			)
			(layer "F.Fab")
		)
		(fp_line
			(start 0.67945 0.3048)
			(end 0.120396 0.3048)
			(stroke
				(width 0.1)
				(type default)
			)
			(layer "F.Fab")
		)
		(fp_line
			(start 0.120396 0.3048)
			(end 0.120396 0.2794)
			(stroke
				(width 0.1)
				(type default)
			)
			(layer "F.Fab")
		)
		(fp_line
			(start -0.12065 0.3048)
			(end -0.67945 0.3048)
			(stroke
				(width 0.1)
				(type default)
			)
			(layer "F.Fab")
		)
		(fp_line
			(start -0.67945 0.3048)
			(end -0.67945 -0.305054)
			(stroke
				(width 0.1)
				(type default)
			)
			(layer "F.Fab")
		)
		(pad "1" smd circle
			(at -0.40005 0 90)
			(size 0 0)
			(layers "F.Cu" "F.Mask" "F.Paste")
			(net "P3V3_AUX")
		)
		(pad "2" smd circle
			(at 0.40005 0 90)
			(size 0 0)
			(layers "F.Cu" "F.Mask" "F.Paste")
			(net "P12V_SCM_ADC_ALERT_R")
		)
	)
)
